# S9S_MB_2U (Grand Teton) — schematic netlist excerpt (pin names and nets, part order shuffled) for the footprints in the layout excerpt that follows; sources: Cadence DE-HDL packaged netlist, KiCad conversion of 03242023_DA0F0TMBIJ0_F0T_Motherboard_J_brd_V01_OCP.brd

PR1327  Q_RES  8.45K 1% CHIP  pkg 0402LF  page 262 : A = P1V05_PCH_AUX_CS ; B = GND

(kicad_pcb
	(version 20260206)
	(generator "pcbnew")
	(generator_version "10.0")
	(general
		(thickness 1.6)
		(legacy_teardrops no)
	)
	(paper "A4")
	(title_block
		(title "03242023_DA0F0TMBIJ0_F0T_Motherboard_J_brd_V01_OCP.brd")
		(comment 1 "Grand Teton / footprints 3739-3739 of 6105")
	)
	(layers
		(0 "F.Cu" signal "TOP")
		(4 "In1.Cu" signal "GND")
		(6 "In2.Cu" signal "IN1")
		(8 "In3.Cu" signal "GND1")
		(10 "In4.Cu" signal "IN2")
		(12 "In5.Cu" signal "GND2")
		(14 "In6.Cu" signal "IN3")
		(16 "In7.Cu" signal "GND3")
		(18 "In8.Cu" signal "VCC")
		(20 "In9.Cu" signal "VCC1")
		(22 "In10.Cu" signal "GND4")
		(24 "In11.Cu" signal "IN4")
		(26 "In12.Cu" signal "GND5")
		(28 "In13.Cu" signal "IN5")
		(30 "In14.Cu" signal "GND6")
		(32 "In15.Cu" signal "IN6")
		(34 "In16.Cu" signal "GND7")
		(2 "B.Cu" signal "BOTTOM")
		(9 "F.Adhes" user "F.Adhesive")
		(11 "B.Adhes" user "B.Adhesive")
		(13 "F.Paste" user "Package Geometry/Pastemask Top")
		(15 "B.Paste" user "Package Geometry/Pastemask Bottom")
		(5 "F.SilkS" user "Ref Des/Silkscreen Top")
		(7 "B.SilkS" user "Ref Des/Silkscreen Bottom")
		(1 "F.Mask" user "Board Geometry/Soldermask Top")
		(3 "B.Mask" user "Board Geometry/Soldermask Bottom")
		(17 "Dwgs.User" user "User.Drawings")
		(19 "Cmts.User" user "User.Comments")
		(21 "Eco1.User" user "User.Eco1")
		(23 "Eco2.User" user "User.Eco2")
		(25 "Edge.Cuts" user "Board Geometry/Outline")
		(27 "Margin" user)
		(31 "F.CrtYd" user "Package Geometry/Place Bound Top")
		(29 "B.CrtYd" user "Package Geometry/Place Bound Bottom")
		(35 "F.Fab" user "Ref Des/Assembly Top")
		(33 "B.Fab" user "Ref Des/Assembly Bottom")
	)
	(footprint ""
		(layer "F.Cu")
		(at 263.805924 -75.61834 90)
		(property "Reference" "PR1327"
			(at 0 0 90)
			(layer "F.SilkS")
			(hide yes)
			(effects
				(font
					(size 1.27 1.27)
				)
			)
		)
		(property "Value" ""
			(at 0 0 90)
			(layer "F.Fab")
			(effects
				(font
					(size 1.27 1.27)
				)
			)
		)
		(duplicate_pad_numbers_are_jumpers no)
		(fp_line
			(start 0.7874 -0.4064)
			(end 0.7874 0.4064)
			(stroke
				(width 0.1524)
				(type default)
			)
			(layer "F.SilkS")
		)
		(fp_line
			(start -0.7874 -0.4064)
			(end 0.7874 -0.4064)
			(stroke
				(width 0.1524)
				(type default)
			)
			(layer "F.SilkS")
		)
		(fp_line
			(start 0.7874 0.4064)
			(end -0.7874 0.4064)
			(stroke
				(width 0.1524)
				(type default)
			)
			(layer "F.SilkS")
		)
		(fp_line
			(start -0.7874 0.4064)
			(end -0.7874 -0.4064)
			(stroke
				(width 0.1524)
				(type default)
			)
			(layer "F.SilkS")
		)
		(fp_line
			(start -0.12065 -0.305054)
			(end -0.12065 -0.2794)
			(stroke
				(width 0.1)
				(type default)
			)
			(layer "F.Fab")
		)
		(fp_line
			(start -0.67945 -0.305054)
			(end -0.12065 -0.305054)
			(stroke
				(width 0.1)
				(type default)
			)
			(layer "F.Fab")
		)
		(fp_line
			(start 0.67945 -0.3048)
			(end 0.67945 0.3048)
			(stroke
				(width 0.1)
				(type default)
			)
			(layer "F.Fab")
		)
		(fp_line
			(start 0.12065 -0.3048)
			(end 0.67945 -0.3048)
			(stroke
				(width 0.1)
				(type default)
			)
			(layer "F.Fab")
		)
		(fp_line
			(start 0.12065 -0.2794)
			(end 0.12065 -0.3048)
			(stroke
				(width 0.1)
				(type default)
			)
			(layer "F.Fab")
		)
		(fp_line
			(start -0.12065 -0.2794)
			(end 0.12065 -0.2794)
			(stroke
				(width 0.1)
				(type default)
			)
			(layer "F.Fab")
		)
		(fp_line
			(start 0.120396 0.2794)
			(end -0.12065 0.2794)
			(stroke
				(width 0.1)
				(type default)
			)
			(layer "F.Fab")
		)
		(fp_line
			(start -0.12065 0.2794)
			(end -0.12065 0.3048)
			(stroke
				(width 0.1)
				(type default)
			)
			(layer "F.Fab")
		)
		(fp_line
			(start 0.67945 0.3048)
			(end 0.120396 0.3048)
			(stroke
				(width 0.1)
				(type default)
			)
			(layer "F.Fab")
		)
		(fp_line
			(start 0.120396 0.3048)
			(end 0.120396 0.2794)
			(stroke
				(width 0.1)
				(type default)
			)
			(layer "F.Fab")
		)
		(fp_line
			(start -0.12065 0.3048)
			(end -0.67945 0.3048)
			(stroke
				(width 0.1)
				(type default)
			)
			(layer "F.Fab")
		)
		(fp_line
			(start -0.67945 0.3048)
			(end -0.67945 -0.305054)
			(stroke
				(width 0.1)
				(type default)
			)
			(layer "F.Fab")
		)
		(pad "1" smd circle
			(at -0.40005 0 90)
			(size 0 0)
			(layers "F.Cu" "F.Mask" "F.Paste")
			(net "P1V05_PCH_AUX_CS")
		)
		(pad "2" smd circle
			(at 0.40005 0 90)
			(size 0 0)
			(layers "F.Cu" "F.Mask" "F.Paste")
			(net "GND")
		)
	)
)
